(kicad_pcb
	(version 20260206)
	(generator "pcbnew")
	(generator_version "10.0")
	(general
		(thickness 1.6)
		(legacy_teardrops no)
	)
	(paper "A4")
	(title_block
		(title "03242023_DA0F0TMBIJ0_F0T_Motherboard_J_brd_V01_OCP.brd")
		(comment 1 "Grand Teton / footprints 4838-4844 of 6105")
	)
	(layers
		(0 "F.Cu" signal "TOP")
		(4 "In1.Cu" signal "GND")
		(6 "In2.Cu" signal "IN1")
		(8 "In3.Cu" signal "GND1")
		(10 "In4.Cu" signal "IN2")
		(12 "In5.Cu" signal "GND2")
		(14 "In6.Cu" signal "IN3")
		(16 "In7.Cu" signal "GND3")
		(18 "In8.Cu" signal "VCC")
		(20 "In9.Cu" signal "VCC1")
		(22 "In10.Cu" signal "GND4")
		(24 "In11.Cu" signal "IN4")
		(26 "In12.Cu" signal "GND5")
		(28 "In13.Cu" signal "IN5")
		(30 "In14.Cu" signal "GND6")
		(32 "In15.Cu" signal "IN6")
		(34 "In16.Cu" signal "GND7")
		(2 "B.Cu" signal "BOTTOM")
		(9 "F.Adhes" user "F.Adhesive")
		(11 "B.Adhes" user "B.Adhesive")
		(13 "F.Paste" user "Package Geometry/Pastemask Top")
		(15 "B.Paste" user "Package Geometry/Pastemask Bottom")
		(5 "F.SilkS" user "Ref Des/Silkscreen Top")
		(7 "B.SilkS" user "Ref Des/Silkscreen Bottom")
		(1 "F.Mask" user "Board Geometry/Soldermask Top")
		(3 "B.Mask" user "Board Geometry/Soldermask Bottom")
		(17 "Dwgs.User" user "User.Drawings")
		(19 "Cmts.User" user "User.Comments")
		(21 "Eco1.User" user "User.Eco1")
		(23 "Eco2.User" user "User.Eco2")
		(25 "Edge.Cuts" user "Board Geometry/Outline")
		(27 "Margin" user)
		(31 "F.CrtYd" user "Package Geometry/Place Bound Top")
		(29 "B.CrtYd" user "Package Geometry/Place Bound Bottom")
		(35 "F.Fab" user "Ref Des/Assembly Top")
		(33 "B.Fab" user "Ref Des/Assembly Bottom")
	)
	(footprint ""
		(layer "B.Cu")
		(at 272.949416 -318.644016)
		(property "Reference" "R30"
			(at 0 0 0)
			(layer "B.SilkS")
			(hide yes)
			(effects
				(font
					(size 1.27 1.27)
				)
				(justify mirror)
			)
		)
		(property "Value" ""
			(at 0 0 0)
			(layer "B.Fab")
			(effects
				(font
					(size 1.27 1.27)
				)
				(justify mirror)
			)
		)
		(duplicate_pad_numbers_are_jumpers no)
		(fp_line
			(start -0.7874 -0.4064)
			(end -0.7874 0.4064)
			(stroke
				(width 0.1524)
				(type default)
			)
			(layer "B.SilkS")
		)
		(fp_line
			(start -0.7874 0.4064)
			(end 0.7874 0.4064)
			(stroke
				(width 0.1524)
				(type default)
			)
			(layer "B.SilkS")
		)
		(fp_line
			(start 0.7874 -0.4064)
			(end -0.7874 -0.4064)
			(stroke
				(width 0.1524)
				(type default)
			)
			(layer "B.SilkS")
		)
		(fp_line
			(start 0.7874 0.4064)
			(end 0.7874 -0.4064)
			(stroke
				(width 0.1524)
				(type default)
			)
			(layer "B.SilkS")
		)
		(fp_line
			(start -0.67945 -0.3048)
			(end -0.67945 0.3048)
			(stroke
				(width 0.1)
				(type default)
			)
			(layer "B.Fab")
		)
		(fp_line
			(start -0.67945 0.3048)
			(end -0.120396 0.3048)
			(stroke
				(width 0.1)
				(type default)
			)
			(layer "B.Fab")
		)
		(fp_line
			(start -0.12065 -0.3048)
			(end -0.67945 -0.3048)
			(stroke
				(width 0.1)
				(type default)
			)
			(layer "B.Fab")
		)
		(fp_line
			(start -0.12065 -0.2794)
			(end -0.12065 -0.3048)
			(stroke
				(width 0.1)
				(type default)
			)
			(layer "B.Fab")
		)
		(fp_line
			(start -0.120396 0.2794)
			(end 0.12065 0.2794)
			(stroke
				(width 0.1)
				(type default)
			)
			(layer "B.Fab")
		)
		(fp_line
			(start -0.120396 0.3048)
			(end -0.120396 0.2794)
			(stroke
				(width 0.1)
				(type default)
			)
			(layer "B.Fab")
		)
		(fp_line
			(start 0.12065 -0.305054)
			(end 0.12065 -0.2794)
			(stroke
				(width 0.1)
				(type default)
			)
			(layer "B.Fab")
		)
		(fp_line
			(start 0.12065 -0.2794)
			(end -0.12065 -0.2794)
			(stroke
				(width 0.1)
				(type default)
			)
			(layer "B.Fab")
		)
		(fp_line
			(start 0.12065 0.2794)
			(end 0.12065 0.3048)
			(stroke
				(width 0.1)
				(type default)
			)
			(layer "B.Fab")
		)
		(fp_line
			(start 0.12065 0.3048)
			(end 0.67945 0.3048)
			(stroke
				(width 0.1)
				(type default)
			)
			(layer "B.Fab")
		)
		(fp_line
			(start 0.67945 -0.305054)
			(end 0.12065 -0.305054)
			(stroke
				(width 0.1)
				(type default)
			)
			(layer "B.Fab")
		)
		(fp_line
			(start 0.67945 0.3048)
			(end 0.67945 -0.305054)
			(stroke
				(width 0.1)
				(type default)
			)
			(layer "B.Fab")
		)
		(pad "1" smd circle
			(at 0.40005 0 180)
			(size 0 0)
			(layers "B.Cu" "B.Mask" "B.Paste")
			(net "PD_CHC_CPU0_DIMM1_SAA")
		)
		(pad "2" smd circle
			(at -0.40005 0 180)
			(size 0 0)
			(layers "B.Cu" "B.Mask" "B.Paste")
			(net "GND")
		)
	)
	(footprint ""
		(layer "B.Cu")
		(at 345.992196 -333.639922 90)
		(property "Reference" "PC303_P0_1"
			(at 0 0 90)
			(layer "B.SilkS")
			(hide yes)
			(effects
				(font
					(size 1.27 1.27)
				)
				(justify mirror)
			)
		)
		(property "Value" ""
			(at 0 0 90)
			(layer "B.Fab")
			(effects
				(font
					(size 1.27 1.27)
				)
				(justify mirror)
			)
		)
		(duplicate_pad_numbers_are_jumpers no)
		(fp_line
			(start 1.524 -0.762)
			(end -1.524 -0.762)
			(stroke
				(width 0.1524)
				(type default)
			)
			(layer "B.SilkS")
		)
		(fp_line
			(start -1.524 -0.762)
			(end -1.524 0.762)
			(stroke
				(width 0.1524)
				(type default)
			)
			(layer "B.SilkS")
		)
		(fp_line
			(start 1.524 0.762)
			(end 1.524 -0.762)
			(stroke
				(width 0.1524)
				(type default)
			)
			(layer "B.SilkS")
		)
		(fp_line
			(start -1.524 0.762)
			(end 1.524 0.762)
			(stroke
				(width 0.1524)
				(type default)
			)
			(layer "B.SilkS")
		)
		(fp_line
			(start 1.1049 -0.724916)
			(end 1.1049 0.724916)
			(stroke
				(width 0.1)
				(type default)
			)
			(layer "B.Fab")
		)
		(fp_line
			(start -1.1049 -0.724916)
			(end 1.1049 -0.724916)
			(stroke
				(width 0.1)
				(type default)
			)
			(layer "B.Fab")
		)
		(fp_line
			(start 1.1049 0.724916)
			(end -1.1049 0.724916)
			(stroke
				(width 0.1)
				(type default)
			)
			(layer "B.Fab")
		)
		(fp_line
			(start -1.1049 0.724916)
			(end -1.1049 -0.724916)
			(stroke
				(width 0.1)
				(type default)
			)
			(layer "B.Fab")
		)
		(pad "1" smd rect
			(at 0.889 0 90)
			(size 1.016 1.27)
			(layers "B.Cu" "B.Mask" "B.Paste")
			(net "SW_P12V_PVCCIN_CPU0_FLT")
		)
		(pad "2" smd rect
			(at -0.889 0 90)
			(size 1.016 1.27)
			(layers "B.Cu" "B.Mask" "B.Paste")
			(net "GND")
		)
	)
	(footprint ""
		(layer "B.Cu")
		(at 77.776578 -343.927938 -90)
		(property "Reference" "PR288"
			(at 0 0 90)
			(layer "B.SilkS")
			(hide yes)
			(effects
				(font
					(size 1.27 1.27)
				)
				(justify mirror)
			)
		)
		(property "Value" ""
			(at 0 0 90)
			(layer "B.Fab")
			(effects
				(font
					(size 1.27 1.27)
				)
				(justify mirror)
			)
		)
		(duplicate_pad_numbers_are_jumpers no)
		(fp_line
			(start -0.7874 0.4064)
			(end 0.7874 0.4064)
			(stroke
				(width 0.1524)
				(type default)
			)
			(layer "B.SilkS")
		)
		(fp_line
			(start 0.7874 0.4064)
			(end 0.7874 -0.4064)
			(stroke
				(width 0.1524)
				(type default)
			)
			(layer "B.SilkS")
		)
		(fp_line
			(start -0.7874 -0.4064)
			(end -0.7874 0.4064)
			(stroke
				(width 0.1524)
				(type default)
			)
			(layer "B.SilkS")
		)
		(fp_line
			(start 0.7874 -0.4064)
			(end -0.7874 -0.4064)
			(stroke
				(width 0.1524)
				(type default)
			)
			(layer "B.SilkS")
		)
		(fp_line
			(start -0.67945 0.3048)
			(end -0.120396 0.3048)
			(stroke
				(width 0.1)
				(type default)
			)
			(layer "B.Fab")
		)
		(fp_line
			(start -0.120396 0.3048)
			(end -0.120396 0.2794)
			(stroke
				(width 0.1)
				(type default)
			)
			(layer "B.Fab")
		)
		(fp_line
			(start 0.12065 0.3048)
			(end 0.67945 0.3048)
			(stroke
				(width 0.1)
				(type default)
			)
			(layer "B.Fab")
		)
		(fp_line
			(start 0.67945 0.3048)
			(end 0.67945 -0.305054)
			(stroke
				(width 0.1)
				(type default)
			)
			(layer "B.Fab")
		)
		(fp_line
			(start -0.120396 0.2794)
			(end 0.12065 0.2794)
			(stroke
				(width 0.1)
				(type default)
			)
			(layer "B.Fab")
		)
		(fp_line
			(start 0.12065 0.2794)
			(end 0.12065 0.3048)
			(stroke
				(width 0.1)
				(type default)
			)
			(layer "B.Fab")
		)
		(fp_line
			(start -0.12065 -0.2794)
			(end -0.12065 -0.3048)
			(stroke
				(width 0.1)
				(type default)
			)
			(layer "B.Fab")
		)
		(fp_line
			(start 0.12065 -0.2794)
			(end -0.12065 -0.2794)
			(stroke
				(width 0.1)
				(type default)
			)
			(layer "B.Fab")
		)
		(fp_line
			(start -0.67945 -0.3048)
			(end -0.67945 0.3048)
			(stroke
				(width 0.1)
				(type default)
			)
			(layer "B.Fab")
		)
		(fp_line
			(start -0.12065 -0.3048)
			(end -0.67945 -0.3048)
			(stroke
				(width 0.1)
				(type default)
			)
			(layer "B.Fab")
		)
		(fp_line
			(start 0.12065 -0.305054)
			(end 0.12065 -0.2794)
			(stroke
				(width 0.1)
				(type default)
			)
			(layer "B.Fab")
		)
		(fp_line
			(start 0.67945 -0.305054)
			(end 0.12065 -0.305054)
			(stroke
				(width 0.1)
				(type default)
			)
			(layer "B.Fab")
		)
		(pad "1" smd circle
			(at 0.40005 0 90)
			(size 0 0)
			(layers "B.Cu" "B.Mask" "B.Paste")
			(net "PVCCIN_CPU1_PVCC")
		)
		(pad "2" smd circle
			(at -0.40005 0 90)
			(size 0 0)
			(layers "B.Cu" "B.Mask" "B.Paste")
			(net "PVCCIN_CPU1_VDD7")
		)
	)
	(footprint ""
		(layer "B.Cu")
		(at 107.887008 -210.194144 180)
		(property "Reference" "C468"
			(at 0 0 0)
			(layer "B.SilkS")
			(hide yes)
			(effects
				(font
					(size 1.27 1.27)
				)
				(justify mirror)
			)
		)
		(property "Value" ""
			(at 0 0 0)
			(layer "B.Fab")
			(effects
				(font
					(size 1.27 1.27)
				)
				(justify mirror)
			)
		)
		(duplicate_pad_numbers_are_jumpers no)
		(fp_line
			(start 1.524 0.762)
			(end 1.524 -0.762)
			(stroke
				(width 0.1524)
				(type default)
			)
			(layer "B.SilkS")
		)
		(fp_line
			(start 1.524 -0.762)
			(end -1.524 -0.762)
			(stroke
				(width 0.1524)
				(type default)
			)
			(layer "B.SilkS")
		)
		(fp_line
			(start -1.524 0.762)
			(end 1.524 0.762)
			(stroke
				(width 0.1524)
				(type default)
			)
			(layer "B.SilkS")
		)
		(fp_line
			(start -1.524 -0.762)
			(end -1.524 0.762)
			(stroke
				(width 0.1524)
				(type default)
			)
			(layer "B.SilkS")
		)
		(fp_line
			(start 1.1049 0.724916)
			(end -1.1049 0.724916)
			(stroke
				(width 0.1)
				(type default)
			)
			(layer "B.Fab")
		)
		(fp_line
			(start 1.1049 -0.724916)
			(end 1.1049 0.724916)
			(stroke
				(width 0.1)
				(type default)
			)
			(layer "B.Fab")
		)
		(fp_line
			(start -1.1049 0.724916)
			(end -1.1049 -0.724916)
			(stroke
				(width 0.1)
				(type default)
			)
			(layer "B.Fab")
		)
		(fp_line
			(start -1.1049 -0.724916)
			(end 1.1049 -0.724916)
			(stroke
				(width 0.1)
				(type default)
			)
			(layer "B.Fab")
		)
		(pad "1" smd rect
			(at 0.889 0 180)
			(size 1.016 1.27)
			(layers "B.Cu" "B.Mask" "B.Paste")
			(net "PVCCFA_EHV_CPU1")
		)
		(pad "2" smd rect
			(at -0.889 0 180)
			(size 1.016 1.27)
			(layers "B.Cu" "B.Mask" "B.Paste")
			(net "GND")
		)
	)
	(footprint ""
		(layer "B.Cu")
		(at 19.760946 -321.554856 -90)
		(property "Reference" "C97"
			(at 0 0 90)
			(layer "B.SilkS")
			(hide yes)
			(effects
				(font
					(size 1.27 1.27)
				)
				(justify mirror)
			)
		)
		(property "Value" ""
			(at 0 0 90)
			(layer "B.Fab")
			(effects
				(font
					(size 1.27 1.27)
				)
				(justify mirror)
			)
		)
		(duplicate_pad_numbers_are_jumpers no)
		(fp_line
			(start -1.524 0.762)
			(end 1.524 0.762)
			(stroke
				(width 0.1524)
				(type default)
			)
			(layer "B.SilkS")
		)
		(fp_line
			(start 1.524 0.762)
			(end 1.524 -0.762)
			(stroke
				(width 0.1524)
				(type default)
			)
			(layer "B.SilkS")
		)
		(fp_line
			(start -1.524 -0.762)
			(end -1.524 0.762)
			(stroke
				(width 0.1524)
				(type default)
			)
			(layer "B.SilkS")
		)
		(fp_line
			(start 1.524 -0.762)
			(end -1.524 -0.762)
			(stroke
				(width 0.1524)
				(type default)
			)
			(layer "B.SilkS")
		)
		(fp_line
			(start -1.1049 0.724916)
			(end -1.1049 -0.724916)
			(stroke
				(width 0.1)
				(type default)
			)
			(layer "B.Fab")
		)
		(fp_line
			(start 1.1049 0.724916)
			(end -1.1049 0.724916)
			(stroke
				(width 0.1)
				(type default)
			)
			(layer "B.Fab")
		)
		(fp_line
			(start -1.1049 -0.724916)
			(end 1.1049 -0.724916)
			(stroke
				(width 0.1)
				(type default)
			)
			(layer "B.Fab")
		)
		(fp_line
			(start 1.1049 -0.724916)
			(end 1.1049 0.724916)
			(stroke
				(width 0.1)
				(type default)
			)
			(layer "B.Fab")
		)
		(pad "1" smd rect
			(at 0.889 0 270)
			(size 1.016 1.27)
			(layers "B.Cu" "B.Mask" "B.Paste")
			(net "P12V_S3_AUX_CPU1_NVDIMM")
		)
		(pad "2" smd rect
			(at -0.889 0 270)
			(size 1.016 1.27)
			(layers "B.Cu" "B.Mask" "B.Paste")
			(net "GND")
		)
	)
	(footprint ""
		(layer "B.Cu")
		(at 422.939718 -363.098588 -90)
		(property "Reference" "PR1299"
			(at 0 0 90)
			(layer "B.SilkS")
			(hide yes)
			(effects
				(font
					(size 1.27 1.27)
				)
				(justify mirror)
			)
		)
		(property "Value" ""
			(at 0 0 90)
			(layer "B.Fab")
			(effects
				(font
					(size 1.27 1.27)
				)
				(justify mirror)
			)
		)
		(duplicate_pad_numbers_are_jumpers no)
		(fp_line
			(start -0.7874 0.4064)
			(end 0.7874 0.4064)
			(stroke
				(width 0.1524)
				(type default)
			)
			(layer "B.SilkS")
		)
		(fp_line
			(start 0.7874 0.4064)
			(end 0.7874 -0.4064)
			(stroke
				(width 0.1524)
				(type default)
			)
			(layer "B.SilkS")
		)
		(fp_line
			(start -0.7874 -0.4064)
			(end -0.7874 0.4064)
			(stroke
				(width 0.1524)
				(type default)
			)
			(layer "B.SilkS")
		)
		(fp_line
			(start 0.7874 -0.4064)
			(end -0.7874 -0.4064)
			(stroke
				(width 0.1524)
				(type default)
			)
			(layer "B.SilkS")
		)
		(fp_line
			(start -0.67945 0.3048)
			(end -0.120396 0.3048)
			(stroke
				(width 0.1)
				(type default)
			)
			(layer "B.Fab")
		)
		(fp_line
			(start -0.120396 0.3048)
			(end -0.120396 0.2794)
			(stroke
				(width 0.1)
				(type default)
			)
			(layer "B.Fab")
		)
		(fp_line
			(start 0.12065 0.3048)
			(end 0.67945 0.3048)
			(stroke
				(width 0.1)
				(type default)
			)
			(layer "B.Fab")
		)
		(fp_line
			(start 0.67945 0.3048)
			(end 0.67945 -0.305054)
			(stroke
				(width 0.1)
				(type default)
			)
			(layer "B.Fab")
		)
		(fp_line
			(start -0.120396 0.2794)
			(end 0.12065 0.2794)
			(stroke
				(width 0.1)
				(type default)
			)
			(layer "B.Fab")
		)
		(fp_line
			(start 0.12065 0.2794)
			(end 0.12065 0.3048)
			(stroke
				(width 0.1)
				(type default)
			)
			(layer "B.Fab")
		)
		(fp_line
			(start -0.12065 -0.2794)
			(end -0.12065 -0.3048)
			(stroke
				(width 0.1)
				(type default)
			)
			(layer "B.Fab")
		)
		(fp_line
			(start 0.12065 -0.2794)
			(end -0.12065 -0.2794)
			(stroke
				(width 0.1)
				(type default)
			)
			(layer "B.Fab")
		)
		(fp_line
			(start -0.67945 -0.3048)
			(end -0.67945 0.3048)
			(stroke
				(width 0.1)
				(type default)
			)
			(layer "B.Fab")
		)
		(fp_line
			(start -0.12065 -0.3048)
			(end -0.67945 -0.3048)
			(stroke
				(width 0.1)
				(type default)
			)
			(layer "B.Fab")
		)
		(fp_line
			(start 0.12065 -0.305054)
			(end 0.12065 -0.2794)
			(stroke
				(width 0.1)
				(type default)
			)
			(layer "B.Fab")
		)
		(fp_line
			(start 0.67945 -0.305054)
			(end 0.12065 -0.305054)
			(stroke
				(width 0.1)
				(type default)
			)
			(layer "B.Fab")
		)
		(pad "1" smd circle
			(at 0.40005 0 90)
			(size 0 0)
			(layers "B.Cu" "B.Mask" "B.Paste")
			(net "PVCCFA_EHV_FIVRA_CPU0_PVCC1")
		)
		(pad "2" smd circle
			(at -0.40005 0 90)
			(size 0 0)
			(layers "B.Cu" "B.Mask" "B.Paste")
			(net "PVCCFA_EHV_FIVRA_CPU0_VDD3")
		)
	)
	(footprint ""
		(layer "B.Cu")
		(at 178.9557 -112.57534 90)
		(property "Reference" "C1928"
			(at 0 0 90)
			(layer "B.SilkS")
			(hide yes)
			(effects
				(font
					(size 1.27 1.27)
				)
				(justify mirror)
			)
		)
		(property "Value" ""
			(at 0 0 90)
			(layer "B.Fab")
			(effects
				(font
					(size 1.27 1.27)
				)
				(justify mirror)
			)
		)
		(duplicate_pad_numbers_are_jumpers no)
		(fp_line
			(start 0.69215 -0.2921)
			(end -0.69215 -0.2921)
			(stroke
				(width 0.1524)
				(type default)
			)
			(layer "B.SilkS")
		)
		(fp_line
			(start -0.69215 -0.2921)
			(end -0.69215 0.2921)
			(stroke
				(width 0.1524)
				(type default)
			)
			(layer "B.SilkS")
		)
		(fp_line
			(start 0.69215 0.2921)
			(end 0.69215 -0.2921)
			(stroke
				(width 0.1524)
				(type default)
			)
			(layer "B.SilkS")
		)
		(fp_line
			(start -0.69215 0.2921)
			(end 0.69215 0.2921)
			(stroke
				(width 0.1524)
				(type default)
			)
			(layer "B.SilkS")
		)
		(fp_line
			(start 0.51435 -0.2794)
			(end -0.51435 -0.2794)
			(stroke
				(width 0.1)
				(type default)
			)
			(layer "B.Fab")
		)
		(fp_line
			(start -0.51435 -0.2794)
			(end -0.51435 0.2794)
			(stroke
				(width 0.1)
				(type default)
			)
			(layer "B.Fab")
		)
		(fp_line
			(start 0.51435 0.2794)
			(end 0.51435 -0.2794)
			(stroke
				(width 0.1)
				(type default)
			)
			(layer "B.Fab")
		)
		(fp_line
			(start -0.51435 0.2794)
			(end 0.51435 0.2794)
			(stroke
				(width 0.1)
				(type default)
			)
			(layer "B.Fab")
		)
		(pad "1" smd circle
			(at 0.40005 0 270)
			(size 0 0)
			(layers "B.Cu" "B.Mask" "B.Paste")
			(net "VCC_PLD_CORE")
		)
		(pad "2" smd circle
			(at -0.40005 0 270)
			(size 0 0)
			(layers "B.Cu" "B.Mask" "B.Paste")
			(net "GND")
		)
		(zone
			(layer "B.Cu")
			(hatch none 0.5)
			(connect_pads
				(clearance 0)
			)
			(min_thickness 0.25)
			(keepout
				(tracks not_allowed)
				(vias allowed)
				(pads allowed)
				(copperpour not_allowed)
				(footprints allowed)
			)
			(placement
				(enabled no)
				(sheetname "")
			)
			(fill
				(thermal_gap 0.5)
				(thermal_bridge_width 0.5)
				(island_removal_mode 0)
			)
			(polygon
				(pts
					(xy 179.04333 -112.76584) (xy 179.101496 -112.6744) (xy 179.101496 -112.47501) (xy 179.04333 -112.38484)
					(xy 178.86807 -112.38484) (xy 178.80965 -112.47501) (xy 178.80965 -112.6744) (xy 178.867816 -112.76584)
				)
			)
		)
	)
)
